(kicad_pcb
	(version 20260206)
	(generator "pcbnew")
	(generator_version "10.0")
	(general
		(thickness 1.6)
		(legacy_teardrops no)
	)
	(paper "A4")
	(title_block
		(title "timecard-production-celestica-r4006 — R4006-B0001-02_R01.brd")
		(comment 1 "Time Appliance Project (Time Card) / footprints 881-886 of 1113")
	)
	(layers
		(0 "F.Cu" signal "TOP")
		(4 "In1.Cu" signal "L02_GND1")
		(6 "In2.Cu" signal "L03_SIG1")
		(8 "In3.Cu" signal "L04_GND2")
		(10 "In4.Cu" signal "L05_VCC1")
		(12 "In5.Cu" signal "L06_VCC2")
		(14 "In6.Cu" signal "L07_GND3")
		(16 "In7.Cu" signal "L08_SIG2")
		(18 "In8.Cu" signal "L09_GND4")
		(2 "B.Cu" signal "BOTTOM")
		(9 "F.Adhes" user "F.Adhesive")
		(11 "B.Adhes" user "B.Adhesive")
		(13 "F.Paste" user "Package Geometry/Pastemask Top")
		(15 "B.Paste" user "Package Geometry/Pastemask Bottom")
		(5 "F.SilkS" user "Ref Des/Silkscreen Top")
		(7 "B.SilkS" user "Ref Des/Silkscreen Bottom")
		(1 "F.Mask" user "Board Geometry/Soldermask Top")
		(3 "B.Mask" user "Board Geometry/Soldermask Bottom")
		(17 "Dwgs.User" user "User.Drawings")
		(19 "Cmts.User" user "User.Comments")
		(21 "Eco1.User" user "User.Eco1")
		(23 "Eco2.User" user "User.Eco2")
		(25 "Edge.Cuts" user "Board Geometry/Outline")
		(27 "Margin" user)
		(31 "F.CrtYd" user "Package Geometry/Place Bound Top")
		(29 "B.CrtYd" user "Package Geometry/Place Bound Bottom")
		(35 "F.Fab" user "Ref Des/Assembly Top")
		(33 "B.Fab" user "Ref Des/Assembly Bottom")
	)
	(footprint ""
		(layer "B.Cu")
		(at 102.84714 -35.323018 -90)
		(property "Reference" "C213"
			(at 1.668018 43.56989 270)
			(unlocked yes)
			(layer "B.SilkS")
			(effects
				(font
					(size 0.635 0.4064)
					(thickness 0.1524)
				)
				(justify mirror)
			)
		)
		(property "Value" "VAL*"
			(at 0 3.718306 270)
			(unlocked yes)
			(layer "B.Fab")
			(hide yes)
			(effects
				(font
					(size 0.7874 0.5842)
					(thickness 0.127)
				)
				(justify mirror)
			)
		)
		(property "Tolerance" "TOL*"
			(at 0 4.861306 270)
			(unlocked yes)
			(layer "Cmts.User")
			(hide yes)
			(effects
				(font
					(size 0.7874 0.5842)
					(thickness 0.127)
				)
				(justify mirror)
			)
		)
		(property "User Part Number" "PARTNUM*"
			(at 0 2.575306 270)
			(unlocked yes)
			(layer "Cmts.User")
			(hide yes)
			(effects
				(font
					(size 0.7874 0.5842)
					(thickness 0.127)
				)
				(justify mirror)
			)
		)
		(property "Device Type" "CAPACITOR-G105-0B104-CK,0.1UF,A"
			(at 0 1.432306 270)
			(unlocked yes)
			(layer "B.Fab")
			(hide yes)
			(effects
				(font
					(size 0.7874 0.5842)
					(thickness 0.127)
				)
				(justify mirror)
			)
		)
		(duplicate_pad_numbers_are_jumpers no)
		(fp_line
			(start -0.970026 0.4699)
			(end 0.970026 0.4699)
			(stroke
				(width 0.1)
				(type default)
			)
			(layer "B.SilkS")
		)
		(fp_line
			(start 0.970026 0.4699)
			(end 0.970026 -0.4699)
			(stroke
				(width 0.1)
				(type default)
			)
			(layer "B.SilkS")
		)
		(fp_line
			(start -0.970026 -0.4699)
			(end -0.970026 0.4699)
			(stroke
				(width 0.1)
				(type default)
			)
			(layer "B.SilkS")
		)
		(fp_line
			(start 0.970026 -0.4699)
			(end -0.970026 -0.4699)
			(stroke
				(width 0.1)
				(type default)
			)
			(layer "B.SilkS")
		)
		(fp_poly
			(pts
				(xy 0.970026 0.4699) (xy -0.970026 0.4699) (xy -0.970026 -0.4699) (xy 0.970026 -0.4699)
			)
			(stroke
				(width 0)
				(type default)
			)
			(fill no)
			(layer "B.CrtYd")
		)
		(fp_line
			(start -0.508 0.3048)
			(end 0.508 0.3048)
			(stroke
				(width 0.1)
				(type default)
			)
			(layer "B.Fab")
		)
		(fp_line
			(start 0.508 0.3048)
			(end 0.508 -0.3048)
			(stroke
				(width 0.1)
				(type default)
			)
			(layer "B.Fab")
		)
		(fp_line
			(start -0.508 -0.3048)
			(end -0.508 0.3048)
			(stroke
				(width 0.1)
				(type default)
			)
			(layer "B.Fab")
		)
		(fp_line
			(start 0.508 -0.3048)
			(end -0.508 -0.3048)
			(stroke
				(width 0.1)
				(type default)
			)
			(layer "B.Fab")
		)
		(pad "1" smd circle
			(at 0.500126 0 90)
			(size 0.635 0.635)
			(layers "B.Cu" "B.Mask" "B.Paste")
			(net "XP2R5V_FPGA")
		)
		(pad "2" smd circle
			(at -0.500126 0 90)
			(size 0.635 0.635)
			(layers "B.Cu" "B.Mask" "B.Paste")
			(net "SG")
		)
	)
	(footprint ""
		(layer "B.Cu")
		(at 145.8214 -99.2378 180)
		(property "Reference" "R16"
			(at -3.1496 -0.09017 0)
			(unlocked yes)
			(layer "B.SilkS")
			(effects
				(font
					(size 0.7874 0.5842)
					(thickness 0.1524)
				)
				(justify mirror)
			)
		)
		(property "Value" "VAL*"
			(at -0.0508 2.245106 180)
			(unlocked yes)
			(layer "B.Fab")
			(hide yes)
			(effects
				(font
					(size 0.7874 0.5842)
					(thickness 0.1524)
				)
				(justify mirror)
			)
		)
		(property "Tolerance" "TOL*"
			(at -0.0508 3.261106 180)
			(unlocked yes)
			(layer "Cmts.User")
			(hide yes)
			(effects
				(font
					(size 0.7874 0.5842)
					(thickness 0.1524)
				)
				(justify mirror)
			)
		)
		(property "Device Type" "RESISTOR-G155-03921-01,3.92KOHA"
			(at -0.0762 1.254506 180)
			(unlocked yes)
			(layer "B.Fab")
			(hide yes)
			(effects
				(font
					(size 0.7874 0.5842)
					(thickness 0.1524)
				)
				(justify mirror)
			)
		)
		(property "User Part Number" "PARTNUM*"
			(at -0.0762 4.302506 180)
			(unlocked yes)
			(layer "Cmts.User")
			(hide yes)
			(effects
				(font
					(size 0.7874 0.5842)
					(thickness 0.1524)
				)
				(justify mirror)
			)
		)
		(duplicate_pad_numbers_are_jumpers no)
		(fp_line
			(start 1.143 0.5588)
			(end -1.143 0.5588)
			(stroke
				(width 0.1)
				(type default)
			)
			(layer "B.SilkS")
		)
		(fp_line
			(start 1.143 -0.5588)
			(end 1.143 0.5588)
			(stroke
				(width 0.1)
				(type default)
			)
			(layer "B.SilkS")
		)
		(fp_line
			(start -1.143 0.5588)
			(end -1.143 -0.5588)
			(stroke
				(width 0.1)
				(type default)
			)
			(layer "B.SilkS")
		)
		(fp_line
			(start -1.143 -0.5588)
			(end 1.143 -0.5588)
			(stroke
				(width 0.1)
				(type default)
			)
			(layer "B.SilkS")
		)
		(fp_rect
			(start 1.143 -0.5588)
			(end -1.143 0.5588)
			(stroke
				(width 0)
				(type default)
			)
			(fill no)
			(layer "B.CrtYd")
		)
		(fp_line
			(start 0.508 0.3048)
			(end -0.508 0.3048)
			(stroke
				(width 0.1)
				(type default)
			)
			(layer "B.Fab")
		)
		(fp_line
			(start 0.508 -0.3048)
			(end 0.508 0.3048)
			(stroke
				(width 0.1)
				(type default)
			)
			(layer "B.Fab")
		)
		(fp_line
			(start -0.508 0.3048)
			(end -0.508 -0.3048)
			(stroke
				(width 0.1)
				(type default)
			)
			(layer "B.Fab")
		)
		(fp_line
			(start -0.508 -0.3048)
			(end 0.508 -0.3048)
			(stroke
				(width 0.1)
				(type default)
			)
			(layer "B.Fab")
		)
		(pad "1" smd rect
			(at 0.5334 0)
			(size 0.7112 0.6096)
			(layers "B.Cu" "B.Mask" "B.Paste")
			(net "XP12R0V_A_FLTB")
		)
		(pad "2" smd rect
			(at -0.5334 0)
			(size 0.7112 0.6096)
			(layers "B.Cu" "B.Mask" "B.Paste")
			(net "SG")
		)
		(zone
			(layer "B.Cu")
			(hatch none 0.5)
			(connect_pads
				(clearance 0)
			)
			(min_thickness 0.25)
			(keepout
				(tracks allowed)
				(vias not_allowed)
				(pads allowed)
				(copperpour not_allowed)
				(footprints allowed)
			)
			(placement
				(enabled no)
				(sheetname "")
			)
			(fill
				(thermal_gap 0.5)
				(thermal_bridge_width 0.5)
				(island_removal_mode 0)
			)
			(polygon
				(pts
					(xy 145.7452 -98.933) (xy 145.8976 -98.933) (xy 145.8976 -99.5426) (xy 145.7452 -99.5426)
				)
			)
		)
	)
	(footprint ""
		(layer "B.Cu")
		(at 63.784988 -15.367 -90)
		(property "Reference" "C25"
			(at 2.032 -0.191262 270)
			(unlocked yes)
			(layer "B.SilkS")
			(effects
				(font
					(size 0.635 0.4064)
					(thickness 0.1524)
				)
				(justify mirror)
			)
		)
		(property "Value" "VAL*"
			(at -0.0762 2.067306 270)
			(unlocked yes)
			(layer "B.Fab")
			(hide yes)
			(effects
				(font
					(size 0.7874 0.5842)
					(thickness 0.1524)
				)
				(justify mirror)
			)
		)
		(property "Tolerance" "TOL*"
			(at -0.0762 3.032506 270)
			(unlocked yes)
			(layer "Cmts.User")
			(hide yes)
			(effects
				(font
					(size 0.7874 0.5842)
					(thickness 0.1524)
				)
				(justify mirror)
			)
		)
		(property "User Part Number" "PARTNUM*"
			(at -0.1016 4.023106 270)
			(unlocked yes)
			(layer "Cmts.User")
			(hide yes)
			(effects
				(font
					(size 0.7874 0.5842)
					(thickness 0.1524)
				)
				(justify mirror)
			)
		)
		(property "Device Type" "CAPACITOR-G105-0B104-CK,0.1UF,A"
			(at -0.0508 1.127506 270)
			(unlocked yes)
			(layer "B.Fab")
			(hide yes)
			(effects
				(font
					(size 0.7874 0.5842)
					(thickness 0.1524)
				)
				(justify mirror)
			)
		)
		(duplicate_pad_numbers_are_jumpers no)
		(fp_line
			(start -1.143 0.5588)
			(end -1.143 -0.5588)
			(stroke
				(width 0.1)
				(type default)
			)
			(layer "B.SilkS")
		)
		(fp_line
			(start 1.143 0.5588)
			(end -1.143 0.5588)
			(stroke
				(width 0.1)
				(type default)
			)
			(layer "B.SilkS")
		)
		(fp_line
			(start -1.143 -0.5588)
			(end 1.143 -0.5588)
			(stroke
				(width 0.1)
				(type default)
			)
			(layer "B.SilkS")
		)
		(fp_line
			(start 1.143 -0.5588)
			(end 1.143 0.5588)
			(stroke
				(width 0.1)
				(type default)
			)
			(layer "B.SilkS")
		)
		(fp_rect
			(start 1.143 0.5588)
			(end -1.143 -0.5588)
			(stroke
				(width 0)
				(type default)
			)
			(fill no)
			(layer "B.CrtYd")
		)
		(fp_line
			(start -0.508 0.3048)
			(end -0.508 -0.3048)
			(stroke
				(width 0.1)
				(type default)
			)
			(layer "B.Fab")
		)
		(fp_line
			(start 0.508 0.3048)
			(end -0.508 0.3048)
			(stroke
				(width 0.1)
				(type default)
			)
			(layer "B.Fab")
		)
		(fp_line
			(start -0.508 -0.3048)
			(end 0.508 -0.3048)
			(stroke
				(width 0.1)
				(type default)
			)
			(layer "B.Fab")
		)
		(fp_line
			(start 0.508 -0.3048)
			(end 0.508 0.3048)
			(stroke
				(width 0.1)
				(type default)
			)
			(layer "B.Fab")
		)
		(pad "1" smd rect
			(at 0.5334 0 90)
			(size 0.7112 0.6096)
			(layers "B.Cu" "B.Mask" "B.Paste")
			(net "C_CPU_RX_PCIE_MGT0_TXN")
		)
		(pad "2" smd rect
			(at -0.5334 0 90)
			(size 0.7112 0.6096)
			(layers "B.Cu" "B.Mask" "B.Paste")
			(net "CPU_RX_PCIE_MGT0_TXN")
		)
		(zone
			(layer "B.Cu")
			(hatch none 0.5)
			(connect_pads
				(clearance 0)
			)
			(min_thickness 0.25)
			(keepout
				(tracks allowed)
				(vias not_allowed)
				(pads allowed)
				(copperpour not_allowed)
				(footprints allowed)
			)
			(placement
				(enabled no)
				(sheetname "")
			)
			(fill
				(thermal_gap 0.5)
				(thermal_bridge_width 0.5)
				(island_removal_mode 0)
			)
			(polygon
				(pts
					(xy 63.480188 -15.2908) (xy 64.089788 -15.2908) (xy 64.089788 -15.4432) (xy 63.480188 -15.4432)
				)
			)
		)
	)
	(footprint ""
		(layer "B.Cu")
		(at 145.288 -50.546 180)
		(property "Reference" "R253"
			(at -0.254 -1.81737 0)
			(unlocked yes)
			(layer "B.SilkS")
			(effects
				(font
					(size 0.7874 0.5842)
					(thickness 0.1524)
				)
				(justify mirror)
			)
		)
		(property "Value" "VAL*"
			(at -0.0508 3.159506 180)
			(unlocked yes)
			(layer "B.Fab")
			(hide yes)
			(effects
				(font
					(size 0.7874 0.5842)
					(thickness 0.1524)
				)
				(justify mirror)
			)
		)
		(property "Tolerance" "TOL*"
			(at -0.0508 4.124706 180)
			(unlocked yes)
			(layer "Cmts.User")
			(hide yes)
			(effects
				(font
					(size 0.7874 0.5842)
					(thickness 0.1524)
				)
				(justify mirror)
			)
		)
		(property "User Part Number" "PARTNUM*"
			(at -0.0508 5.089906 180)
			(unlocked yes)
			(layer "Cmts.User")
			(hide yes)
			(effects
				(font
					(size 0.7874 0.5842)
					(thickness 0.1524)
				)
				(justify mirror)
			)
		)
		(property "Device Type" "RESISTOR-G157-12R20-01,2.2OHM,A"
			(at 0 2.194306 180)
			(unlocked yes)
			(layer "B.Fab")
			(hide yes)
			(effects
				(font
					(size 0.7874 0.5842)
					(thickness 0.1524)
				)
				(justify mirror)
			)
		)
		(duplicate_pad_numbers_are_jumpers no)
		(fp_line
			(start 1.5748 0.9398)
			(end -1.5748 0.9398)
			(stroke
				(width 0.1)
				(type default)
			)
			(layer "B.SilkS")
		)
		(fp_line
			(start 1.5748 -0.9398)
			(end 1.5748 0.9398)
			(stroke
				(width 0.1)
				(type default)
			)
			(layer "B.SilkS")
		)
		(fp_line
			(start -1.5748 0.9398)
			(end -1.5748 -0.9398)
			(stroke
				(width 0.1)
				(type default)
			)
			(layer "B.SilkS")
		)
		(fp_line
			(start -1.5748 -0.9398)
			(end 1.5748 -0.9398)
			(stroke
				(width 0.1)
				(type default)
			)
			(layer "B.SilkS")
		)
		(fp_rect
			(start -1.5748 -0.9398)
			(end 1.5748 0.9398)
			(stroke
				(width 0)
				(type default)
			)
			(fill no)
			(layer "B.CrtYd")
		)
		(fp_line
			(start 1.016 0.635)
			(end -1.016 0.635)
			(stroke
				(width 0.1)
				(type default)
			)
			(layer "B.Fab")
		)
		(fp_line
			(start 1.016 -0.635)
			(end 1.016 0.635)
			(stroke
				(width 0.1)
				(type default)
			)
			(layer "B.Fab")
		)
		(fp_line
			(start -1.016 0.635)
			(end -1.016 -0.635)
			(stroke
				(width 0.1)
				(type default)
			)
			(layer "B.Fab")
		)
		(fp_line
			(start -1.016 -0.635)
			(end 1.016 -0.635)
			(stroke
				(width 0.1)
				(type default)
			)
			(layer "B.Fab")
		)
		(pad "1" smd rect
			(at 0.8382 0)
			(size 0.9652 1.3716)
			(layers "B.Cu" "B.Mask" "B.Paste")
			(net "UNNAMED_523_CAPACITOR_I31_2")
		)
		(pad "2" smd rect
			(at -0.8382 0)
			(size 0.9652 1.3716)
			(layers "B.Cu" "B.Mask" "B.Paste")
			(net "SG")
		)
		(zone
			(layer "B.Cu")
			(hatch none 0.5)
			(connect_pads
				(clearance 0)
			)
			(min_thickness 0.25)
			(keepout
				(tracks allowed)
				(vias not_allowed)
				(pads allowed)
				(copperpour not_allowed)
				(footprints allowed)
			)
			(placement
				(enabled no)
				(sheetname "")
			)
			(fill
				(thermal_gap 0.5)
				(thermal_bridge_width 0.5)
				(island_removal_mode 0)
			)
			(polygon
				(pts
					(xy 145.5166 -49.911) (xy 145.5166 -51.181) (xy 145.0594 -51.181) (xy 145.0594 -49.911)
				)
			)
		)
	)
	(footprint ""
		(layer "B.Cu")
		(at 137.16 -46.228 -90)
		(property "Reference" "C179"
			(at 0 -1.87833 270)
			(unlocked yes)
			(layer "B.SilkS")
			(effects
				(font
					(size 0.7874 0.5842)
					(thickness 0.1524)
				)
				(justify mirror)
			)
		)
		(property "Value" "VAL*"
			(at -0.0762 3.134106 270)
			(unlocked yes)
			(layer "B.Fab")
			(hide yes)
			(effects
				(font
					(size 0.7874 0.5842)
					(thickness 0.1524)
				)
				(justify mirror)
			)
		)
		(property "Tolerance" "TOL*"
			(at -0.0762 4.048506 270)
			(unlocked yes)
			(layer "Cmts.User")
			(hide yes)
			(effects
				(font
					(size 0.7874 0.5842)
					(thickness 0.1524)
				)
				(justify mirror)
			)
		)
		(property "User Part Number" "PARTNUM*"
			(at -0.1016 5.013706 270)
			(unlocked yes)
			(layer "Cmts.User")
			(hide yes)
			(effects
				(font
					(size 0.7874 0.5842)
					(thickness 0.1524)
				)
				(justify mirror)
			)
		)
		(property "Device Type" "CAPACITOR-G107-0F476-AM,47UF,2A"
			(at -0.0508 2.194306 270)
			(unlocked yes)
			(layer "B.Fab")
			(hide yes)
			(effects
				(font
					(size 0.7874 0.5842)
					(thickness 0.1524)
				)
				(justify mirror)
			)
		)
		(duplicate_pad_numbers_are_jumpers no)
		(fp_line
			(start -1.5748 0.9398)
			(end -1.5748 -0.9398)
			(stroke
				(width 0.1)
				(type default)
			)
			(layer "B.SilkS")
		)
		(fp_line
			(start 1.5748 0.9398)
			(end -1.5748 0.9398)
			(stroke
				(width 0.1)
				(type default)
			)
			(layer "B.SilkS")
		)
		(fp_line
			(start -1.5748 -0.9398)
			(end 1.5748 -0.9398)
			(stroke
				(width 0.1)
				(type default)
			)
			(layer "B.SilkS")
		)
		(fp_line
			(start 1.5748 -0.9398)
			(end 1.5748 0.9398)
			(stroke
				(width 0.1)
				(type default)
			)
			(layer "B.SilkS")
		)
		(fp_rect
			(start 1.5748 0.9398)
			(end -1.5748 -0.9398)
			(stroke
				(width 0)
				(type default)
			)
			(fill no)
			(layer "B.CrtYd")
		)
		(fp_line
			(start -1.016 0.635)
			(end -1.016 -0.635)
			(stroke
				(width 0.1)
				(type default)
			)
			(layer "B.Fab")
		)
		(fp_line
			(start 1.016 0.635)
			(end -1.016 0.635)
			(stroke
				(width 0.1)
				(type default)
			)
			(layer "B.Fab")
		)
		(fp_line
			(start -1.016 -0.635)
			(end 1.016 -0.635)
			(stroke
				(width 0.1)
				(type default)
			)
			(layer "B.Fab")
		)
		(fp_line
			(start 1.016 -0.635)
			(end 1.016 0.635)
			(stroke
				(width 0.1)
				(type default)
			)
			(layer "B.Fab")
		)
		(pad "1" smd rect
			(at 0.8382 0 90)
			(size 0.9652 1.3716)
			(layers "B.Cu" "B.Mask" "B.Paste")
			(net "XP1R0V_FPGA")
		)
		(pad "2" smd rect
			(at -0.8382 0 90)
			(size 0.9652 1.3716)
			(layers "B.Cu" "B.Mask" "B.Paste")
			(net "SG")
		)
		(zone
			(layer "B.Cu")
			(hatch none 0.5)
			(connect_pads
				(clearance 0)
			)
			(min_thickness 0.25)
			(keepout
				(tracks allowed)
				(vias not_allowed)
				(pads allowed)
				(copperpour not_allowed)
				(footprints allowed)
			)
			(placement
				(enabled no)
				(sheetname "")
			)
			(fill
				(thermal_gap 0.5)
				(thermal_bridge_width 0.5)
				(island_removal_mode 0)
			)
			(polygon
				(pts
					(xy 136.525 -45.9994) (xy 137.795 -45.9994) (xy 137.795 -46.4566) (xy 136.525 -46.4566)
				)
			)
		)
	)
	(footprint ""
		(layer "B.Cu")
		(at 111.847122 -40.323008 90)
		(property "Reference" "C171"
			(at -1.397508 -42.018712 270)
			(unlocked yes)
			(layer "B.SilkS")
			(effects
				(font
					(size 0.635 0.4064)
					(thickness 0.1524)
				)
				(justify mirror)
			)
		)
		(property "Value" "VAL*"
			(at 0 3.718306 90)
			(unlocked yes)
			(layer "B.Fab")
			(hide yes)
			(effects
				(font
					(size 0.7874 0.5842)
					(thickness 0.127)
				)
				(justify mirror)
			)
		)
		(property "Tolerance" "TOL*"
			(at 0 4.861306 90)
			(unlocked yes)
			(layer "Cmts.User")
			(hide yes)
			(effects
				(font
					(size 0.7874 0.5842)
					(thickness 0.127)
				)
				(justify mirror)
			)
		)
		(property "User Part Number" "PARTNUM*"
			(at 0 2.575306 90)
			(unlocked yes)
			(layer "Cmts.User")
			(hide yes)
			(effects
				(font
					(size 0.7874 0.5842)
					(thickness 0.127)
				)
				(justify mirror)
			)
		)
		(property "Device Type" "CAPACITOR-G105-0B104-CK,0.1UF,A"
			(at 0 1.432306 90)
			(unlocked yes)
			(layer "B.Fab")
			(hide yes)
			(effects
				(font
					(size 0.7874 0.5842)
					(thickness 0.127)
				)
				(justify mirror)
			)
		)
		(duplicate_pad_numbers_are_jumpers no)
		(fp_line
			(start 0.970026 -0.4699)
			(end -0.970026 -0.4699)
			(stroke
				(width 0.1)
				(type default)
			)
			(layer "B.SilkS")
		)
		(fp_line
			(start -0.970026 -0.4699)
			(end -0.970026 0.4699)
			(stroke
				(width 0.1)
				(type default)
			)
			(layer "B.SilkS")
		)
		(fp_line
			(start 0.970026 0.4699)
			(end 0.970026 -0.4699)
			(stroke
				(width 0.1)
				(type default)
			)
			(layer "B.SilkS")
		)
		(fp_line
			(start -0.970026 0.4699)
			(end 0.970026 0.4699)
			(stroke
				(width 0.1)
				(type default)
			)
			(layer "B.SilkS")
		)
		(fp_poly
			(pts
				(xy 0.970026 0.4699) (xy -0.970026 0.4699) (xy -0.970026 -0.4699) (xy 0.970026 -0.4699)
			)
			(stroke
				(width 0)
				(type default)
			)
			(fill no)
			(layer "B.CrtYd")
		)
		(fp_line
			(start 0.508 -0.3048)
			(end -0.508 -0.3048)
			(stroke
				(width 0.1)
				(type default)
			)
			(layer "B.Fab")
		)
		(fp_line
			(start -0.508 -0.3048)
			(end -0.508 0.3048)
			(stroke
				(width 0.1)
				(type default)
			)
			(layer "B.Fab")
		)
		(fp_line
			(start 0.508 0.3048)
			(end 0.508 -0.3048)
			(stroke
				(width 0.1)
				(type default)
			)
			(layer "B.Fab")
		)
		(fp_line
			(start -0.508 0.3048)
			(end 0.508 0.3048)
			(stroke
				(width 0.1)
				(type default)
			)
			(layer "B.Fab")
		)
		(pad "1" smd circle
			(at 0.500126 0 270)
			(size 0.635 0.635)
			(layers "B.Cu" "B.Mask" "B.Paste")
			(net "XP1R0V_FPGA_VCCINT")
		)
		(pad "2" smd circle
			(at -0.500126 0 270)
			(size 0.635 0.635)
			(layers "B.Cu" "B.Mask" "B.Paste")
			(net "SG")
		)
	)
)
